(kicad_pcb
	(version 20260206)
	(generator "pcbnew")
	(generator_version "10.0")
	(general
		(thickness 1.6)
		(legacy_teardrops no)
	)
	(paper "A4")
	(title_block
		(title "03242023_DA0F0TMBIJ0_F0T_Motherboard_J_brd_V01_OCP.brd")
		(comment 1 "Grand Teton / footprints 2446-2453 of 6105")
	)
	(layers
		(0 "F.Cu" signal "TOP")
		(4 "In1.Cu" signal "GND")
		(6 "In2.Cu" signal "IN1")
		(8 "In3.Cu" signal "GND1")
		(10 "In4.Cu" signal "IN2")
		(12 "In5.Cu" signal "GND2")
		(14 "In6.Cu" signal "IN3")
		(16 "In7.Cu" signal "GND3")
		(18 "In8.Cu" signal "VCC")
		(20 "In9.Cu" signal "VCC1")
		(22 "In10.Cu" signal "GND4")
		(24 "In11.Cu" signal "IN4")
		(26 "In12.Cu" signal "GND5")
		(28 "In13.Cu" signal "IN5")
		(30 "In14.Cu" signal "GND6")
		(32 "In15.Cu" signal "IN6")
		(34 "In16.Cu" signal "GND7")
		(2 "B.Cu" signal "BOTTOM")
		(9 "F.Adhes" user "F.Adhesive")
		(11 "B.Adhes" user "B.Adhesive")
		(13 "F.Paste" user "Package Geometry/Pastemask Top")
		(15 "B.Paste" user "Package Geometry/Pastemask Bottom")
		(5 "F.SilkS" user "Ref Des/Silkscreen Top")
		(7 "B.SilkS" user "Ref Des/Silkscreen Bottom")
		(1 "F.Mask" user "Board Geometry/Soldermask Top")
		(3 "B.Mask" user "Board Geometry/Soldermask Bottom")
		(17 "Dwgs.User" user "User.Drawings")
		(19 "Cmts.User" user "User.Comments")
		(21 "Eco1.User" user "User.Eco1")
		(23 "Eco2.User" user "User.Eco2")
		(25 "Edge.Cuts" user "Board Geometry/Outline")
		(27 "Margin" user)
		(31 "F.CrtYd" user "Package Geometry/Place Bound Top")
		(29 "B.CrtYd" user "Package Geometry/Place Bound Bottom")
		(35 "F.Fab" user "Ref Des/Assembly Top")
		(33 "B.Fab" user "Ref Des/Assembly Bottom")
	)
	(footprint ""
		(layer "F.Cu")
		(at 364.50143 -238.162338 90)
		(property "Reference" "C410"
			(at 0 0 90)
			(layer "F.SilkS")
			(hide yes)
			(effects
				(font
					(size 1.27 1.27)
				)
			)
		)
		(property "Value" ""
			(at 0 0 90)
			(layer "F.Fab")
			(effects
				(font
					(size 1.27 1.27)
				)
			)
		)
		(duplicate_pad_numbers_are_jumpers no)
		(fp_line
			(start 0.7874 -0.4064)
			(end 0.7874 0.4064)
			(stroke
				(width 0.1524)
				(type default)
			)
			(layer "F.SilkS")
		)
		(fp_line
			(start -0.7874 -0.4064)
			(end 0.7874 -0.4064)
			(stroke
				(width 0.1524)
				(type default)
			)
			(layer "F.SilkS")
		)
		(fp_line
			(start 0.7874 0.4064)
			(end -0.7874 0.4064)
			(stroke
				(width 0.1524)
				(type default)
			)
			(layer "F.SilkS")
		)
		(fp_line
			(start -0.7874 0.4064)
			(end -0.7874 -0.4064)
			(stroke
				(width 0.1524)
				(type default)
			)
			(layer "F.SilkS")
		)
		(fp_line
			(start -0.12065 -0.305054)
			(end -0.12065 -0.2794)
			(stroke
				(width 0.1)
				(type default)
			)
			(layer "F.Fab")
		)
		(fp_line
			(start -0.67945 -0.305054)
			(end -0.12065 -0.305054)
			(stroke
				(width 0.1)
				(type default)
			)
			(layer "F.Fab")
		)
		(fp_line
			(start 0.67945 -0.3048)
			(end 0.67945 0.3048)
			(stroke
				(width 0.1)
				(type default)
			)
			(layer "F.Fab")
		)
		(fp_line
			(start 0.12065 -0.3048)
			(end 0.67945 -0.3048)
			(stroke
				(width 0.1)
				(type default)
			)
			(layer "F.Fab")
		)
		(fp_line
			(start 0.12065 -0.2794)
			(end 0.12065 -0.3048)
			(stroke
				(width 0.1)
				(type default)
			)
			(layer "F.Fab")
		)
		(fp_line
			(start -0.12065 -0.2794)
			(end 0.12065 -0.2794)
			(stroke
				(width 0.1)
				(type default)
			)
			(layer "F.Fab")
		)
		(fp_line
			(start 0.120396 0.2794)
			(end -0.12065 0.2794)
			(stroke
				(width 0.1)
				(type default)
			)
			(layer "F.Fab")
		)
		(fp_line
			(start -0.12065 0.2794)
			(end -0.12065 0.3048)
			(stroke
				(width 0.1)
				(type default)
			)
			(layer "F.Fab")
		)
		(fp_line
			(start 0.67945 0.3048)
			(end 0.120396 0.3048)
			(stroke
				(width 0.1)
				(type default)
			)
			(layer "F.Fab")
		)
		(fp_line
			(start 0.120396 0.3048)
			(end 0.120396 0.2794)
			(stroke
				(width 0.1)
				(type default)
			)
			(layer "F.Fab")
		)
		(fp_line
			(start -0.12065 0.3048)
			(end -0.67945 0.3048)
			(stroke
				(width 0.1)
				(type default)
			)
			(layer "F.Fab")
		)
		(fp_line
			(start -0.67945 0.3048)
			(end -0.67945 -0.305054)
			(stroke
				(width 0.1)
				(type default)
			)
			(layer "F.Fab")
		)
		(pad "1" smd circle
			(at -0.40005 0 90)
			(size 0 0)
			(layers "F.Cu" "F.Mask" "F.Paste")
			(net "PVCCINFAON_CPU0")
		)
		(pad "2" smd circle
			(at 0.40005 0 90)
			(size 0 0)
			(layers "F.Cu" "F.Mask" "F.Paste")
			(net "GND")
		)
	)
	(footprint ""
		(layer "F.Cu")
		(at 435.350158 -118.568216 90)
		(property "Reference" "R2402"
			(at 0 0 90)
			(layer "F.SilkS")
			(hide yes)
			(effects
				(font
					(size 1.27 1.27)
				)
			)
		)
		(property "Value" ""
			(at 0 0 90)
			(layer "F.Fab")
			(effects
				(font
					(size 1.27 1.27)
				)
			)
		)
		(duplicate_pad_numbers_are_jumpers no)
		(fp_line
			(start 0.7874 -0.4064)
			(end 0.7874 0.4064)
			(stroke
				(width 0.1524)
				(type default)
			)
			(layer "F.SilkS")
		)
		(fp_line
			(start -0.7874 -0.4064)
			(end 0.7874 -0.4064)
			(stroke
				(width 0.1524)
				(type default)
			)
			(layer "F.SilkS")
		)
		(fp_line
			(start 0.7874 0.4064)
			(end -0.7874 0.4064)
			(stroke
				(width 0.1524)
				(type default)
			)
			(layer "F.SilkS")
		)
		(fp_line
			(start -0.7874 0.4064)
			(end -0.7874 -0.4064)
			(stroke
				(width 0.1524)
				(type default)
			)
			(layer "F.SilkS")
		)
		(fp_line
			(start -0.12065 -0.305054)
			(end -0.12065 -0.2794)
			(stroke
				(width 0.1)
				(type default)
			)
			(layer "F.Fab")
		)
		(fp_line
			(start -0.67945 -0.305054)
			(end -0.12065 -0.305054)
			(stroke
				(width 0.1)
				(type default)
			)
			(layer "F.Fab")
		)
		(fp_line
			(start 0.67945 -0.3048)
			(end 0.67945 0.3048)
			(stroke
				(width 0.1)
				(type default)
			)
			(layer "F.Fab")
		)
		(fp_line
			(start 0.12065 -0.3048)
			(end 0.67945 -0.3048)
			(stroke
				(width 0.1)
				(type default)
			)
			(layer "F.Fab")
		)
		(fp_line
			(start 0.12065 -0.2794)
			(end 0.12065 -0.3048)
			(stroke
				(width 0.1)
				(type default)
			)
			(layer "F.Fab")
		)
		(fp_line
			(start -0.12065 -0.2794)
			(end 0.12065 -0.2794)
			(stroke
				(width 0.1)
				(type default)
			)
			(layer "F.Fab")
		)
		(fp_line
			(start 0.120396 0.2794)
			(end -0.12065 0.2794)
			(stroke
				(width 0.1)
				(type default)
			)
			(layer "F.Fab")
		)
		(fp_line
			(start -0.12065 0.2794)
			(end -0.12065 0.3048)
			(stroke
				(width 0.1)
				(type default)
			)
			(layer "F.Fab")
		)
		(fp_line
			(start 0.67945 0.3048)
			(end 0.120396 0.3048)
			(stroke
				(width 0.1)
				(type default)
			)
			(layer "F.Fab")
		)
		(fp_line
			(start 0.120396 0.3048)
			(end 0.120396 0.2794)
			(stroke
				(width 0.1)
				(type default)
			)
			(layer "F.Fab")
		)
		(fp_line
			(start -0.12065 0.3048)
			(end -0.67945 0.3048)
			(stroke
				(width 0.1)
				(type default)
			)
			(layer "F.Fab")
		)
		(fp_line
			(start -0.67945 0.3048)
			(end -0.67945 -0.305054)
			(stroke
				(width 0.1)
				(type default)
			)
			(layer "F.Fab")
		)
		(pad "1" smd circle
			(at -0.40005 0 90)
			(size 0 0)
			(layers "F.Cu" "F.Mask" "F.Paste")
			(net "SMB_VR_3V3AUX_SCL_R2")
		)
		(pad "2" smd circle
			(at 0.40005 0 90)
			(size 0 0)
			(layers "F.Cu" "F.Mask" "F.Paste")
			(net "SMB_CLK_PVCCD_HV_CPU0")
		)
	)
	(footprint ""
		(layer "F.Cu")
		(at 197.21068 -41.466516 180)
		(property "Reference" "R4062"
			(at 0 0 180)
			(layer "F.SilkS")
			(hide yes)
			(effects
				(font
					(size 1.27 1.27)
				)
			)
		)
		(property "Value" ""
			(at 0 0 180)
			(layer "F.Fab")
			(effects
				(font
					(size 1.27 1.27)
				)
			)
		)
		(duplicate_pad_numbers_are_jumpers no)
		(fp_line
			(start 0.7874 0.4064)
			(end -0.7874 0.4064)
			(stroke
				(width 0.1524)
				(type default)
			)
			(layer "F.SilkS")
		)
		(fp_line
			(start 0.7874 -0.4064)
			(end 0.7874 0.4064)
			(stroke
				(width 0.1524)
				(type default)
			)
			(layer "F.SilkS")
		)
		(fp_line
			(start -0.7874 0.4064)
			(end -0.7874 -0.4064)
			(stroke
				(width 0.1524)
				(type default)
			)
			(layer "F.SilkS")
		)
		(fp_line
			(start -0.7874 -0.4064)
			(end 0.7874 -0.4064)
			(stroke
				(width 0.1524)
				(type default)
			)
			(layer "F.SilkS")
		)
		(fp_line
			(start 0.67945 0.3048)
			(end 0.120396 0.3048)
			(stroke
				(width 0.1)
				(type default)
			)
			(layer "F.Fab")
		)
		(fp_line
			(start 0.67945 -0.3048)
			(end 0.67945 0.3048)
			(stroke
				(width 0.1)
				(type default)
			)
			(layer "F.Fab")
		)
		(fp_line
			(start 0.12065 -0.2794)
			(end 0.12065 -0.3048)
			(stroke
				(width 0.1)
				(type default)
			)
			(layer "F.Fab")
		)
		(fp_line
			(start 0.12065 -0.3048)
			(end 0.67945 -0.3048)
			(stroke
				(width 0.1)
				(type default)
			)
			(layer "F.Fab")
		)
		(fp_line
			(start 0.120396 0.3048)
			(end 0.120396 0.2794)
			(stroke
				(width 0.1)
				(type default)
			)
			(layer "F.Fab")
		)
		(fp_line
			(start 0.120396 0.2794)
			(end -0.12065 0.2794)
			(stroke
				(width 0.1)
				(type default)
			)
			(layer "F.Fab")
		)
		(fp_line
			(start -0.12065 0.3048)
			(end -0.67945 0.3048)
			(stroke
				(width 0.1)
				(type default)
			)
			(layer "F.Fab")
		)
		(fp_line
			(start -0.12065 0.2794)
			(end -0.12065 0.3048)
			(stroke
				(width 0.1)
				(type default)
			)
			(layer "F.Fab")
		)
		(fp_line
			(start -0.12065 -0.2794)
			(end 0.12065 -0.2794)
			(stroke
				(width 0.1)
				(type default)
			)
			(layer "F.Fab")
		)
		(fp_line
			(start -0.12065 -0.305054)
			(end -0.12065 -0.2794)
			(stroke
				(width 0.1)
				(type default)
			)
			(layer "F.Fab")
		)
		(fp_line
			(start -0.67945 0.3048)
			(end -0.67945 -0.305054)
			(stroke
				(width 0.1)
				(type default)
			)
			(layer "F.Fab")
		)
		(fp_line
			(start -0.67945 -0.305054)
			(end -0.12065 -0.305054)
			(stroke
				(width 0.1)
				(type default)
			)
			(layer "F.Fab")
		)
		(pad "1" smd circle
			(at -0.40005 0 180)
			(size 0 0)
			(layers "F.Cu" "F.Mask" "F.Paste")
			(net "P12V_SCM_EN")
		)
		(pad "2" smd circle
			(at 0.40005 0 180)
			(size 0 0)
			(layers "F.Cu" "F.Mask" "F.Paste")
			(net "P12V_SCM_EN_R")
		)
	)
	(footprint ""
		(layer "F.Cu")
		(at 197.19036 -115.534948 180)
		(property "Reference" "R1465"
			(at 0 0 180)
			(layer "F.SilkS")
			(hide yes)
			(effects
				(font
					(size 1.27 1.27)
				)
			)
		)
		(property "Value" ""
			(at 0 0 180)
			(layer "F.Fab")
			(effects
				(font
					(size 1.27 1.27)
				)
			)
		)
		(duplicate_pad_numbers_are_jumpers no)
		(fp_line
			(start 0.7874 0.4064)
			(end -0.7874 0.4064)
			(stroke
				(width 0.1524)
				(type default)
			)
			(layer "F.SilkS")
		)
		(fp_line
			(start 0.7874 -0.4064)
			(end 0.7874 0.4064)
			(stroke
				(width 0.1524)
				(type default)
			)
			(layer "F.SilkS")
		)
		(fp_line
			(start -0.7874 0.4064)
			(end -0.7874 -0.4064)
			(stroke
				(width 0.1524)
				(type default)
			)
			(layer "F.SilkS")
		)
		(fp_line
			(start -0.7874 -0.4064)
			(end 0.7874 -0.4064)
			(stroke
				(width 0.1524)
				(type default)
			)
			(layer "F.SilkS")
		)
		(fp_line
			(start 0.67945 0.3048)
			(end 0.120396 0.3048)
			(stroke
				(width 0.1)
				(type default)
			)
			(layer "F.Fab")
		)
		(fp_line
			(start 0.67945 -0.3048)
			(end 0.67945 0.3048)
			(stroke
				(width 0.1)
				(type default)
			)
			(layer "F.Fab")
		)
		(fp_line
			(start 0.12065 -0.2794)
			(end 0.12065 -0.3048)
			(stroke
				(width 0.1)
				(type default)
			)
			(layer "F.Fab")
		)
		(fp_line
			(start 0.12065 -0.3048)
			(end 0.67945 -0.3048)
			(stroke
				(width 0.1)
				(type default)
			)
			(layer "F.Fab")
		)
		(fp_line
			(start 0.120396 0.3048)
			(end 0.120396 0.2794)
			(stroke
				(width 0.1)
				(type default)
			)
			(layer "F.Fab")
		)
		(fp_line
			(start 0.120396 0.2794)
			(end -0.12065 0.2794)
			(stroke
				(width 0.1)
				(type default)
			)
			(layer "F.Fab")
		)
		(fp_line
			(start -0.12065 0.3048)
			(end -0.67945 0.3048)
			(stroke
				(width 0.1)
				(type default)
			)
			(layer "F.Fab")
		)
		(fp_line
			(start -0.12065 0.2794)
			(end -0.12065 0.3048)
			(stroke
				(width 0.1)
				(type default)
			)
			(layer "F.Fab")
		)
		(fp_line
			(start -0.12065 -0.2794)
			(end 0.12065 -0.2794)
			(stroke
				(width 0.1)
				(type default)
			)
			(layer "F.Fab")
		)
		(fp_line
			(start -0.12065 -0.305054)
			(end -0.12065 -0.2794)
			(stroke
				(width 0.1)
				(type default)
			)
			(layer "F.Fab")
		)
		(fp_line
			(start -0.67945 0.3048)
			(end -0.67945 -0.305054)
			(stroke
				(width 0.1)
				(type default)
			)
			(layer "F.Fab")
		)
		(fp_line
			(start -0.67945 -0.305054)
			(end -0.12065 -0.305054)
			(stroke
				(width 0.1)
				(type default)
			)
			(layer "F.Fab")
		)
		(pad "1" smd circle
			(at -0.40005 0 180)
			(size 0 0)
			(layers "F.Cu" "F.Mask" "F.Paste")
			(net "P3V3_AUX")
		)
		(pad "2" smd circle
			(at 0.40005 0 180)
			(size 0 0)
			(layers "F.Cu" "F.Mask" "F.Paste")
			(net "IRQ_BMC_CPU_NMI_R1")
		)
	)
	(footprint ""
		(layer "F.Cu")
		(at 137.706354 -408.517344 -90)
		(property "Reference" "C1527"
			(at 0 0 270)
			(layer "F.SilkS")
			(hide yes)
			(effects
				(font
					(size 1.27 1.27)
				)
			)
		)
		(property "Value" ""
			(at 0 0 270)
			(layer "F.Fab")
			(effects
				(font
					(size 1.27 1.27)
				)
			)
		)
		(duplicate_pad_numbers_are_jumpers no)
		(fp_line
			(start -0.299974 0.150114)
			(end -0.299974 -0.150114)
			(stroke
				(width 0.1)
				(type default)
			)
			(layer "F.Fab")
		)
		(fp_line
			(start 0.299974 0.150114)
			(end -0.299974 0.150114)
			(stroke
				(width 0.1)
				(type default)
			)
			(layer "F.Fab")
		)
		(fp_line
			(start -0.299974 -0.150114)
			(end 0.299974 -0.150114)
			(stroke
				(width 0.1)
				(type default)
			)
			(layer "F.Fab")
		)
		(fp_line
			(start 0.299974 -0.150114)
			(end 0.299974 0.150114)
			(stroke
				(width 0.1)
				(type default)
			)
			(layer "F.Fab")
		)
		(pad "1" smd rect
			(at -0.2667 0 270)
			(size 0.3048 0.381)
			(layers "F.Cu" "F.Mask" "F.Paste")
			(net "P5E_CPU1_PE3_TX_C_DP<10>")
		)
		(pad "2" smd rect
			(at 0.2667 0 270)
			(size 0.3048 0.381)
			(layers "F.Cu" "F.Mask" "F.Paste")
			(net "P5E_CPU1_PE3_TX_DP<10>")
		)
	)
	(footprint ""
		(layer "F.Cu")
		(at 106.3244 -249.320558 -90)
		(property "Reference" "C303"
			(at 0 0 270)
			(layer "F.SilkS")
			(hide yes)
			(effects
				(font
					(size 1.27 1.27)
				)
			)
		)
		(property "Value" ""
			(at 0 0 270)
			(layer "F.Fab")
			(effects
				(font
					(size 1.27 1.27)
				)
			)
		)
		(duplicate_pad_numbers_are_jumpers no)
		(fp_line
			(start -0.7874 0.4064)
			(end -0.7874 -0.4064)
			(stroke
				(width 0.1524)
				(type default)
			)
			(layer "F.SilkS")
		)
		(fp_line
			(start 0.7874 0.4064)
			(end -0.7874 0.4064)
			(stroke
				(width 0.1524)
				(type default)
			)
			(layer "F.SilkS")
		)
		(fp_line
			(start -0.7874 -0.4064)
			(end 0.7874 -0.4064)
			(stroke
				(width 0.1524)
				(type default)
			)
			(layer "F.SilkS")
		)
		(fp_line
			(start 0.7874 -0.4064)
			(end 0.7874 0.4064)
			(stroke
				(width 0.1524)
				(type default)
			)
			(layer "F.SilkS")
		)
		(fp_line
			(start -0.67945 0.3048)
			(end -0.67945 -0.305054)
			(stroke
				(width 0.1)
				(type default)
			)
			(layer "F.Fab")
		)
		(fp_line
			(start -0.12065 0.3048)
			(end -0.67945 0.3048)
			(stroke
				(width 0.1)
				(type default)
			)
			(layer "F.Fab")
		)
		(fp_line
			(start 0.120396 0.3048)
			(end 0.120396 0.2794)
			(stroke
				(width 0.1)
				(type default)
			)
			(layer "F.Fab")
		)
		(fp_line
			(start 0.67945 0.3048)
			(end 0.120396 0.3048)
			(stroke
				(width 0.1)
				(type default)
			)
			(layer "F.Fab")
		)
		(fp_line
			(start -0.12065 0.2794)
			(end -0.12065 0.3048)
			(stroke
				(width 0.1)
				(type default)
			)
			(layer "F.Fab")
		)
		(fp_line
			(start 0.120396 0.2794)
			(end -0.12065 0.2794)
			(stroke
				(width 0.1)
				(type default)
			)
			(layer "F.Fab")
		)
		(fp_line
			(start -0.12065 -0.2794)
			(end 0.12065 -0.2794)
			(stroke
				(width 0.1)
				(type default)
			)
			(layer "F.Fab")
		)
		(fp_line
			(start 0.12065 -0.2794)
			(end 0.12065 -0.3048)
			(stroke
				(width 0.1)
				(type default)
			)
			(layer "F.Fab")
		)
		(fp_line
			(start 0.12065 -0.3048)
			(end 0.67945 -0.3048)
			(stroke
				(width 0.1)
				(type default)
			)
			(layer "F.Fab")
		)
		(fp_line
			(start 0.67945 -0.3048)
			(end 0.67945 0.3048)
			(stroke
				(width 0.1)
				(type default)
			)
			(layer "F.Fab")
		)
		(fp_line
			(start -0.67945 -0.305054)
			(end -0.12065 -0.305054)
			(stroke
				(width 0.1)
				(type default)
			)
			(layer "F.Fab")
		)
		(fp_line
			(start -0.12065 -0.305054)
			(end -0.12065 -0.2794)
			(stroke
				(width 0.1)
				(type default)
			)
			(layer "F.Fab")
		)
		(pad "1" smd circle
			(at -0.40005 0 270)
			(size 0 0)
			(layers "F.Cu" "F.Mask" "F.Paste")
			(net "PVCCIN_CPU1")
		)
		(pad "2" smd circle
			(at 0.40005 0 270)
			(size 0 0)
			(layers "F.Cu" "F.Mask" "F.Paste")
			(net "GND")
		)
	)
	(footprint ""
		(layer "F.Cu")
		(at 390.930384 -16.088614 90)
		(property "Reference" "C838"
			(at 0 0 90)
			(layer "F.SilkS")
			(hide yes)
			(effects
				(font
					(size 1.27 1.27)
				)
			)
		)
		(property "Value" ""
			(at 0 0 90)
			(layer "F.Fab")
			(effects
				(font
					(size 1.27 1.27)
				)
			)
		)
		(duplicate_pad_numbers_are_jumpers no)
		(fp_line
			(start 0.299974 -0.150114)
			(end 0.299974 0.150114)
			(stroke
				(width 0.1)
				(type default)
			)
			(layer "F.Fab")
		)
		(fp_line
			(start -0.299974 -0.150114)
			(end 0.299974 -0.150114)
			(stroke
				(width 0.1)
				(type default)
			)
			(layer "F.Fab")
		)
		(fp_line
			(start 0.299974 0.150114)
			(end -0.299974 0.150114)
			(stroke
				(width 0.1)
				(type default)
			)
			(layer "F.Fab")
		)
		(fp_line
			(start -0.299974 0.150114)
			(end -0.299974 -0.150114)
			(stroke
				(width 0.1)
				(type default)
			)
			(layer "F.Fab")
		)
		(pad "1" smd rect
			(at -0.2667 0 90)
			(size 0.3048 0.381)
			(layers "F.Cu" "F.Mask" "F.Paste")
			(net "P5E_CPU0_PE1_TX_C_DN<15>")
		)
		(pad "2" smd rect
			(at 0.2667 0 90)
			(size 0.3048 0.381)
			(layers "F.Cu" "F.Mask" "F.Paste")
			(net "P5E_CPU0_PE1_TX_DN<15>")
		)
	)
	(footprint ""
		(layer "F.Cu")
		(at 159.149034 -408.517344 -90)
		(property "Reference" "C1541"
			(at 0 0 270)
			(layer "F.SilkS")
			(hide yes)
			(effects
				(font
					(size 1.27 1.27)
				)
			)
		)
		(property "Value" ""
			(at 0 0 270)
			(layer "F.Fab")
			(effects
				(font
					(size 1.27 1.27)
				)
			)
		)
		(duplicate_pad_numbers_are_jumpers no)
		(fp_line
			(start -0.299974 0.150114)
			(end -0.299974 -0.150114)
			(stroke
				(width 0.1)
				(type default)
			)
			(layer "F.Fab")
		)
		(fp_line
			(start 0.299974 0.150114)
			(end -0.299974 0.150114)
			(stroke
				(width 0.1)
				(type default)
			)
			(layer "F.Fab")
		)
		(fp_line
			(start -0.299974 -0.150114)
			(end 0.299974 -0.150114)
			(stroke
				(width 0.1)
				(type default)
			)
			(layer "F.Fab")
		)
		(fp_line
			(start 0.299974 -0.150114)
			(end 0.299974 0.150114)
			(stroke
				(width 0.1)
				(type default)
			)
			(layer "F.Fab")
		)
		(pad "1" smd rect
			(at -0.2667 0 270)
			(size 0.3048 0.381)
			(layers "F.Cu" "F.Mask" "F.Paste")
			(net "P5E_CPU1_PE3_TX_C_DP<3>")
		)
		(pad "2" smd rect
			(at 0.2667 0 270)
			(size 0.3048 0.381)
			(layers "F.Cu" "F.Mask" "F.Paste")
			(net "P5E_CPU1_PE3_TX_DP<3>")
		)
	)
)
